(kicad_pcb
	(version 20260206)
	(generator "pcbnew")
	(generator_version "10.0")
	(general
		(thickness 1.6)
		(legacy_teardrops no)
	)
	(paper "A4")
	(title_block
		(title "dpb — 14545-sa.0730WZS0815.brd")
		(comment 1 "Honey Badger (Wiwynn) / footprints 384-386 of 1066")
	)
	(layers
		(0 "F.Cu" signal "TOP")
		(4 "In1.Cu" signal "L2GND")
		(6 "In2.Cu" signal "L3")
		(8 "In3.Cu" signal "L4VCC")
		(10 "In4.Cu" signal "L5VCC")
		(12 "In5.Cu" signal "L6")
		(14 "In6.Cu" signal "L7GND")
		(2 "B.Cu" signal "BOTTOM")
		(9 "F.Adhes" user "F.Adhesive")
		(11 "B.Adhes" user "B.Adhesive")
		(13 "F.Paste" user "Package Geometry/Pastemask Top")
		(15 "B.Paste" user "Package Geometry/Pastemask Bottom")
		(5 "F.SilkS" user "Ref Des/Silkscreen Top")
		(7 "B.SilkS" user "Ref Des/Silkscreen Bottom")
		(1 "F.Mask" user "Board Geometry/Soldermask Top")
		(3 "B.Mask" user "Board Geometry/Soldermask Bottom")
		(17 "Dwgs.User" user "User.Drawings")
		(19 "Cmts.User" user "User.Comments")
		(21 "Eco1.User" user "User.Eco1")
		(23 "Eco2.User" user "User.Eco2")
		(25 "Edge.Cuts" user "Board Geometry/Outline")
		(27 "Margin" user)
		(31 "F.CrtYd" user "Package Geometry/Place Bound Top")
		(29 "B.CrtYd" user "Package Geometry/Place Bound Bottom")
		(35 "F.Fab" user "Ref Des/Assembly Top")
		(33 "B.Fab" user "Ref Des/Assembly Bottom")
	)
	(footprint ""
		(layer "F.Cu")
		(at 17.500092 -26.329894 -90)
		(property "Reference" "SKT15"
			(at 0 0 270)
			(layer "F.SilkS")
			(hide yes)
			(effects
				(font
					(size 1.27 1.27)
				)
			)
		)
		(property "Value" "SKT-SATA14P-15P-12-GP"
			(at -22.6187 8.1788 270)
			(unlocked yes)
			(layer "F.Fab")
			(hide yes)
			(effects
				(font
					(size 1.016 1.016)
					(thickness 0.1524)
				)
			)
		)
		(property "Device Type" "87945-1001"
			(at -22.6187 6.6548 270)
			(unlocked yes)
			(layer "F.Fab")
			(hide yes)
			(effects
				(font
					(size 1.016 1.016)
					(thickness 0.1524)
				)
			)
		)
		(duplicate_pad_numbers_are_jumpers no)
		(fp_line
			(start -20.4724 9.652)
			(end -20.4724 2.3114)
			(stroke
				(width 0.1524)
				(type default)
			)
			(layer "F.SilkS")
		)
		(fp_line
			(start -17.8435 9.652)
			(end -20.4724 9.652)
			(stroke
				(width 0.1524)
				(type default)
			)
			(layer "F.SilkS")
		)
		(fp_line
			(start 17.8435 9.652)
			(end 17.8435 7.9502)
			(stroke
				(width 0.1524)
				(type default)
			)
			(layer "F.SilkS")
		)
		(fp_line
			(start 20.4724 9.652)
			(end 17.8435 9.652)
			(stroke
				(width 0.1524)
				(type default)
			)
			(layer "F.SilkS")
		)
		(fp_line
			(start -17.8435 7.9502)
			(end -17.8435 9.652)
			(stroke
				(width 0.1524)
				(type default)
			)
			(layer "F.SilkS")
		)
		(fp_line
			(start 17.8435 7.9502)
			(end -17.8435 7.9502)
			(stroke
				(width 0.1524)
				(type default)
			)
			(layer "F.SilkS")
		)
		(fp_line
			(start -23.7617 2.3114)
			(end -23.7617 -2.3114)
			(stroke
				(width 0.1524)
				(type default)
			)
			(layer "F.SilkS")
		)
		(fp_line
			(start -20.4724 2.3114)
			(end -23.7617 2.3114)
			(stroke
				(width 0.1524)
				(type default)
			)
			(layer "F.SilkS")
		)
		(fp_line
			(start 20.4724 2.3114)
			(end 20.4724 9.652)
			(stroke
				(width 0.1524)
				(type default)
			)
			(layer "F.SilkS")
		)
		(fp_line
			(start 23.7617 2.3114)
			(end 20.4724 2.3114)
			(stroke
				(width 0.1524)
				(type default)
			)
			(layer "F.SilkS")
		)
		(fp_line
			(start -23.117556 0.5461)
			(end -23.117556 -0.5461)
			(stroke
				(width 0.3048)
				(type default)
			)
			(layer "F.SilkS")
		)
		(fp_line
			(start 20.882356 0.5461)
			(end 20.882356 -0.5461)
			(stroke
				(width 0.3048)
				(type default)
			)
			(layer "F.SilkS")
		)
		(fp_line
			(start -20.882356 -0.5461)
			(end -20.882356 0.5461)
			(stroke
				(width 0.3048)
				(type default)
			)
			(layer "F.SilkS")
		)
		(fp_line
			(start 23.117556 -0.5461)
			(end 23.117556 0.5461)
			(stroke
				(width 0.3048)
				(type default)
			)
			(layer "F.SilkS")
		)
		(fp_line
			(start -23.7617 -2.3114)
			(end -20.4724 -2.3114)
			(stroke
				(width 0.1524)
				(type default)
			)
			(layer "F.SilkS")
		)
		(fp_line
			(start -20.4724 -2.3114)
			(end -20.4724 -5.7658)
			(stroke
				(width 0.1524)
				(type default)
			)
			(layer "F.SilkS")
		)
		(fp_line
			(start 20.4724 -2.3114)
			(end 23.7617 -2.3114)
			(stroke
				(width 0.1524)
				(type default)
			)
			(layer "F.SilkS")
		)
		(fp_line
			(start 23.7617 -2.3114)
			(end 23.7617 2.3114)
			(stroke
				(width 0.1524)
				(type default)
			)
			(layer "F.SilkS")
		)
		(fp_line
			(start -20.4724 -5.7658)
			(end 20.4724 -5.7658)
			(stroke
				(width 0.1524)
				(type default)
			)
			(layer "F.SilkS")
		)
		(fp_line
			(start 20.4724 -5.7658)
			(end 20.4724 -2.3114)
			(stroke
				(width 0.1524)
				(type default)
			)
			(layer "F.SilkS")
		)
		(fp_line
			(start -15.3924 -5.8547)
			(end -16.3576 -5.8547)
			(stroke
				(width 0.3302)
				(type default)
			)
			(layer "F.SilkS")
		)
		(fp_arc
			(start -20.882356 0.5461)
			(mid -21.999956 1.6637)
			(end -23.117556 0.5461)
			(stroke
				(width 0.3048)
				(type default)
			)
			(layer "F.SilkS")
		)
		(fp_arc
			(start 23.117556 0.5461)
			(mid 21.999956 1.6637)
			(end 20.882356 0.5461)
			(stroke
				(width 0.3048)
				(type default)
			)
			(layer "F.SilkS")
		)
		(fp_arc
			(start -23.117556 -0.5461)
			(mid -21.999956 -1.6637)
			(end -20.882356 -0.5461)
			(stroke
				(width 0.3048)
				(type default)
			)
			(layer "F.SilkS")
		)
		(fp_arc
			(start 20.882356 -0.5461)
			(mid 21.999956 -1.6637)
			(end 23.117556 -0.5461)
			(stroke
				(width 0.3048)
				(type default)
			)
			(layer "F.SilkS")
		)
		(fp_poly
			(pts
				(xy -15.87119 -5.838698) (xy -15.23619 -6.473698) (xy -16.50619 -6.473698)
			)
			(stroke
				(width 0)
				(type default)
			)
			(fill yes)
			(layer "F.SilkS")
		)
		(fp_poly
			(pts
				(xy -20.2184 -5.5118) (xy 20.2184 -5.5118) (xy 20.2184 -2.0574) (xy 23.5077 -2.0574) (xy 23.5077 2.0574)
				(xy 20.2184 2.0574) (xy 20.2184 9.398) (xy 18.0975 9.398) (xy 18.0975 7.6962) (xy -18.0975 7.6962)
				(xy -18.0975 9.398) (xy -20.2184 9.398) (xy -20.2184 2.0574) (xy -23.5077 2.0574) (xy -23.5077 -2.0574)
				(xy -20.2184 -2.0574)
			)
			(stroke
				(width 0)
				(type default)
			)
			(fill no)
			(layer "F.CrtYd")
		)
		(fp_poly
			(pts
				(xy -20.2184 -5.5118) (xy -20.2184 -6.0198) (xy -20.7264 -6.0198) (xy -20.7264 -2.5654) (xy -24.0157 -2.5654)
				(xy -24.0157 2.5654) (xy -20.7264 2.5654) (xy -20.7264 9.906) (xy -17.5895 9.906) (xy -17.5895 8.2042)
				(xy 17.5895 8.2042) (xy 17.5895 9.906) (xy 20.7264 9.906) (xy 20.7264 2.5654) (xy 24.0157 2.5654)
				(xy 24.0157 -2.5654) (xy 20.7264 -2.5654) (xy 20.7264 -6.0198) (xy -20.21586 -6.0198) (xy -20.21586 -5.5118)
				(xy 20.2184 -5.5118) (xy 20.2184 -2.0574) (xy 23.5077 -2.0574) (xy 23.5077 2.0574) (xy 20.2184 2.0574)
				(xy 20.2184 9.398) (xy 18.0975 9.398) (xy 18.0975 7.6962) (xy -18.0975 7.6962) (xy -18.0975 9.398)
				(xy -20.2184 9.398) (xy -20.2184 2.0574) (xy -23.5077 2.0574) (xy -23.5077 -2.0574) (xy -20.2184 -2.0574)
			)
			(stroke
				(width 0)
				(type default)
			)
			(fill no)
			(layer "F.CrtYd")
		)
		(fp_poly
			(pts
				(xy -20.7264 -6.0198) (xy -20.7264 -2.5654) (xy -24.0157 -2.5654) (xy -24.0157 2.5654) (xy -20.7264 2.5654)
				(xy -20.7264 9.906) (xy -17.5895 9.906) (xy -17.5895 8.2042) (xy 17.5895 8.2042) (xy 17.5895 9.906)
				(xy 20.7264 9.906) (xy 20.7264 2.5654) (xy 24.0157 2.5654) (xy 24.0157 -2.5654) (xy 20.7264 -2.5654)
				(xy 20.7264 -6.0198)
			)
			(stroke
				(width 0)
				(type default)
			)
			(fill no)
			(layer "F.Fab")
		)
		(pad "" np_thru_hole circle
			(at -18.999962 -2.350008 270)
			(size 0.254 0.254)
			(drill 1.8542)
			(layers "*.Cu" "*.Mask")
			(clearance 1.1557)
			(thermal_gap 1.1557)
		)
		(pad "" np_thru_hole circle
			(at 18.999962 -2.350008 270)
			(size 0.254 0.254)
			(drill 1.8542)
			(layers "*.Cu" "*.Mask")
			(clearance 1.1557)
			(thermal_gap 1.1557)
		)
		(pad "H1" thru_hole oval
			(at -21.999956 0 270)
			(size 1.524 2.6162)
			(drill oval 0.8128 1.905)
			(layers "*.Cu" "*.Mask")
			(remove_unused_layers no)
			(net "GND")
			(clearance 0.1524)
			(thermal_gap 0.1524)
		)
		(pad "H2" thru_hole oval
			(at 21.999956 0 270)
			(size 1.524 2.6162)
			(drill oval 0.8128 1.905)
			(layers "*.Cu" "*.Mask")
			(remove_unused_layers no)
			(net "GND")
			(clearance 0.1524)
			(thermal_gap 0.1524)
		)
		(pad "P1" smd rect
			(at -1.89992 -4.249928 270)
			(size 0.6604 2.3876)
			(layers "F.Cu" "F.Mask" "F.Paste")
			(net "Net_45")
		)
		(pad "P2" smd rect
			(at -0.62992 -4.249928 270)
			(size 0.6604 2.3876)
			(layers "F.Cu" "F.Mask" "F.Paste")
			(net "Net_44")
		)
		(pad "P3" smd rect
			(at 0.64008 -4.249928 270)
			(size 0.6604 2.3876)
			(layers "F.Cu" "F.Mask" "F.Paste")
			(net "Net_43")
		)
		(pad "P4" smd rect
			(at 1.91008 -4.249928 270)
			(size 0.6604 2.3876)
			(layers "F.Cu" "F.Mask" "F.Paste")
			(net "GND")
		)
		(pad "P5" smd rect
			(at 3.18008 -4.249928 270)
			(size 0.6604 2.3876)
			(layers "F.Cu" "F.Mask" "F.Paste")
			(net "HDD_PRSNT_NET14")
		)
		(pad "P6" smd rect
			(at 4.45008 -4.249928 270)
			(size 0.6604 2.3876)
			(layers "F.Cu" "F.Mask" "F.Paste")
			(net "GND")
		)
		(pad "P7" smd rect
			(at 5.72008 -4.249928 270)
			(size 0.6604 2.3876)
			(layers "F.Cu" "F.Mask" "F.Paste")
			(net "5V_PRE_14")
		)
		(pad "P8" smd rect
			(at 6.99008 -4.249928 270)
			(size 0.6604 2.3876)
			(layers "F.Cu" "F.Mask" "F.Paste")
			(net "P5V_HDD14")
		)
		(pad "P9" smd rect
			(at 8.26008 -4.249928 270)
			(size 0.6604 2.3876)
			(layers "F.Cu" "F.Mask" "F.Paste")
			(net "P5V_HDD14")
		)
		(pad "P10" smd rect
			(at 9.53008 -4.249928 270)
			(size 0.6604 2.3876)
			(layers "F.Cu" "F.Mask" "F.Paste")
			(net "GND")
		)
		(pad "P11" smd rect
			(at 10.80008 -4.249928 270)
			(size 0.6604 2.3876)
			(layers "F.Cu" "F.Mask" "F.Paste")
			(net "ACT_HDD14")
		)
		(pad "P12" smd rect
			(at 12.07008 -4.249928 270)
			(size 0.6604 2.3876)
			(layers "F.Cu" "F.Mask" "F.Paste")
			(net "GND")
		)
		(pad "P13" smd rect
			(at 13.34008 -4.249928 270)
			(size 0.6604 2.3876)
			(layers "F.Cu" "F.Mask" "F.Paste")
			(net "12V_PRE_14")
		)
		(pad "P14" smd rect
			(at 14.61008 -4.249928 270)
			(size 0.6604 2.3876)
			(layers "F.Cu" "F.Mask" "F.Paste")
			(net "P12V_HDD14")
		)
		(pad "P15" smd rect
			(at 15.88008 -4.249928 270)
			(size 0.6604 2.3876)
			(layers "F.Cu" "F.Mask" "F.Paste")
			(net "P12V_HDD14")
		)
		(pad "S1" smd rect
			(at -15.86992 -4.249928 270)
			(size 0.6604 2.3876)
			(layers "F.Cu" "F.Mask" "F.Paste")
			(net "GND")
		)
		(pad "S2" smd rect
			(at -14.59992 -4.249928 270)
			(size 0.6604 2.3876)
			(layers "F.Cu" "F.Mask" "F.Paste")
			(net "SAS2X28_A_HDD14_TX_+")
		)
		(pad "S3" smd rect
			(at -13.32992 -4.249928 270)
			(size 0.6604 2.3876)
			(layers "F.Cu" "F.Mask" "F.Paste")
			(net "SAS2X28_A_HDD14_TX_-")
		)
		(pad "S4" smd rect
			(at -12.05992 -4.249928 270)
			(size 0.6604 2.3876)
			(layers "F.Cu" "F.Mask" "F.Paste")
			(net "GND")
		)
		(pad "S5" smd rect
			(at -10.78992 -4.249928 270)
			(size 0.6604 2.3876)
			(layers "F.Cu" "F.Mask" "F.Paste")
			(net "SAS2X28_DRIVE_RX_N_A14")
		)
		(pad "S6" smd rect
			(at -9.51992 -4.249928 270)
			(size 0.6604 2.3876)
			(layers "F.Cu" "F.Mask" "F.Paste")
			(net "SAS2X28_DRIVE_RX_P_A14")
		)
		(pad "S7" smd rect
			(at -8.24992 -4.249928 270)
			(size 0.6604 2.3876)
			(layers "F.Cu" "F.Mask" "F.Paste")
			(net "GND")
		)
		(pad "S8" smd rect
			(at -7.480046 -2.100072 270)
			(size 0.508 1.905)
			(layers "F.Cu" "F.Mask" "F.Paste")
			(net "GND")
		)
		(pad "S9" smd rect
			(at -6.679946 -2.100072 270)
			(size 0.508 1.905)
			(layers "F.Cu" "F.Mask" "F.Paste")
			(net "SAS2X28_B_HDD14_TX_+")
		)
		(pad "S10" smd rect
			(at -5.8801 -2.100072 270)
			(size 0.508 1.905)
			(layers "F.Cu" "F.Mask" "F.Paste")
			(net "SAS2X28_B_HDD14_TX_-")
		)
		(pad "S11" smd rect
			(at -5.08 -2.100072 270)
			(size 0.508 1.905)
			(layers "F.Cu" "F.Mask" "F.Paste")
			(net "GND")
		)
		(pad "S12" smd rect
			(at -4.2799 -2.100072 270)
			(size 0.508 1.905)
			(layers "F.Cu" "F.Mask" "F.Paste")
			(net "SAS2X28_DRIVE_RX_N_B14")
		)
		(pad "S13" smd rect
			(at -3.480054 -2.100072 270)
			(size 0.508 1.905)
			(layers "F.Cu" "F.Mask" "F.Paste")
			(net "SAS2X28_DRIVE_RX_P_B14")
		)
		(pad "S14" smd rect
			(at -2.679954 -2.100072 270)
			(size 0.508 1.905)
			(layers "F.Cu" "F.Mask" "F.Paste")
			(net "GND")
		)
		(zone
			(layers "F.Cu" "B.Cu" "In1.Cu" "In2.Cu" "In3.Cu" "In4.Cu" "In5.Cu" "In6.Cu")
			(hatch none 0.5)
			(connect_pads
				(clearance 0)
			)
			(min_thickness 0.25)
			(keepout
				(tracks not_allowed)
				(vias allowed)
				(pads allowed)
				(copperpour not_allowed)
				(footprints allowed)
			)
			(placement
				(enabled no)
				(sheetname "")
			)
			(fill
				(thermal_gap 0.5)
				(thermal_bridge_width 0.5)
				(island_removal_mode 0)
			)
			(polygon
				(pts
					(arc
						(start 21.082 -45.329856)
						(mid 18.6182 -45.329856)
						(end 21.082 -45.329856)
					)
				)
			)
		)
		(zone
			(layers "F.Cu" "B.Cu" "In1.Cu" "In2.Cu" "In3.Cu" "In4.Cu" "In5.Cu" "In6.Cu")
			(hatch none 0.5)
			(connect_pads
				(clearance 0)
			)
			(min_thickness 0.25)
			(keepout
				(tracks not_allowed)
				(vias allowed)
				(pads allowed)
				(copperpour not_allowed)
				(footprints allowed)
			)
			(placement
				(enabled no)
				(sheetname "")
			)
			(fill
				(thermal_gap 0.5)
				(thermal_bridge_width 0.5)
				(island_removal_mode 0)
			)
			(polygon
				(pts
					(arc
						(start 21.082 -7.329932)
						(mid 18.6182 -7.329932)
						(end 21.082 -7.329932)
					)
				)
			)
		)
	)
	(footprint ""
		(layer "F.Cu")
		(at 14.922246 -166.747698 90)
		(property "Reference" "R282"
			(at 0 0 90)
			(layer "F.SilkS")
			(hide yes)
			(effects
				(font
					(size 1.27 1.27)
				)
			)
		)
		(property "Value" "10KR2F-2-GP"
			(at 0.064008 -3.993896 90)
			(unlocked yes)
			(layer "F.Fab")
			(hide yes)
			(effects
				(font
					(size 1.016 1.016)
					(thickness 0.1524)
				)
			)
		)
		(property "Device Type" "R402H16"
			(at 0.064008 -5.517896 90)
			(unlocked yes)
			(layer "F.Fab")
			(hide yes)
			(effects
				(font
					(size 1.016 1.016)
					(thickness 0.1524)
				)
			)
		)
		(duplicate_pad_numbers_are_jumpers no)
		(fp_line
			(start 0.508 -0.9398)
			(end -0.508 -0.9398)
			(stroke
				(width 0.1524)
				(type default)
			)
			(layer "F.SilkS")
		)
		(fp_line
			(start -0.508 -0.9398)
			(end -0.508 0.9398)
			(stroke
				(width 0.1524)
				(type default)
			)
			(layer "F.SilkS")
		)
		(fp_rect
			(start -0.508 0.9398)
			(end 0.508 -0.9398)
			(stroke
				(width 0)
				(type default)
			)
			(fill no)
			(layer "F.CrtYd")
		)
		(fp_rect
			(start -0.508 0.9398)
			(end 0.508 -0.9398)
			(stroke
				(width 0)
				(type default)
			)
			(fill no)
			(layer "F.Fab")
		)
		(pad "1" smd custom
			(at 0 -0.4445 90)
			(size 0.1397 0.1397)
			(layers "F.Cu" "F.Mask" "F.Paste")
			(net "P5VC")
			(options
				(clearance outline)
				(anchor circle)
			)
			(primitives
				(gr_poly
					(pts
						(arc
							(start -0.1778 -0.2794)
							(mid -0.249642 -0.249642)
							(end -0.2794 -0.1778)
						)
						(arc
							(start -0.2794 0.1778)
							(mid -0.249642 0.249642)
							(end -0.1778 0.2794)
						)
						(arc
							(start 0.1778 0.2794)
							(mid 0.249642 0.249642)
							(end 0.2794 0.1778)
						)
						(arc
							(start 0.2794 -0.1778)
							(mid 0.249642 -0.249642)
							(end 0.1778 -0.2794)
						)
					)
					(width 0)
					(fill yes)
				)
			)
		)
		(pad "2" smd custom
			(at 0 0.4445 90)
			(size 0.1397 0.1397)
			(layers "F.Cu" "F.Mask" "F.Paste")
			(net "DRIVE_ACT_13")
			(options
				(clearance outline)
				(anchor circle)
			)
			(primitives
				(gr_poly
					(pts
						(arc
							(start -0.1778 -0.2794)
							(mid -0.249642 -0.249642)
							(end -0.2794 -0.1778)
						)
						(arc
							(start -0.2794 0.1778)
							(mid -0.249642 0.249642)
							(end -0.1778 0.2794)
						)
						(arc
							(start 0.1778 0.2794)
							(mid 0.249642 0.249642)
							(end 0.2794 0.1778)
						)
						(arc
							(start 0.2794 -0.1778)
							(mid 0.249642 -0.249642)
							(end 0.1778 -0.2794)
						)
					)
					(width 0)
					(fill yes)
				)
			)
		)
	)
	(footprint ""
		(layer "F.Cu")
		(at 198.9328 -384.7338)
		(property "Reference" "C125"
			(at 0 0 0)
			(layer "F.SilkS")
			(hide yes)
			(effects
				(font
					(size 1.27 1.27)
				)
			)
		)
		(property "Value" "SCD1U10V2KX-5GP"
			(at 1.1811 -2.7051 0)
			(unlocked yes)
			(layer "F.Fab")
			(hide yes)
			(effects
				(font
					(size 1.016 1.016)
					(thickness 0.1524)
				)
			)
		)
		(property "Device Type" "C402H22"
			(at 1.1811 -4.2291 0)
			(unlocked yes)
			(layer "F.Fab")
			(hide yes)
			(effects
				(font
					(size 1.016 1.016)
					(thickness 0.1524)
				)
			)
		)
		(duplicate_pad_numbers_are_jumpers no)
		(fp_rect
			(start -0.4318 0.9525)
			(end 0.4318 -0.9525)
			(stroke
				(width 0)
				(type default)
			)
			(fill no)
			(layer "F.CrtYd")
		)
		(fp_rect
			(start -0.4318 0.9525)
			(end 0.4318 -0.9525)
			(stroke
				(width 0)
				(type default)
			)
			(fill no)
			(layer "F.Fab")
		)
		(pad "1" smd custom
			(at 0 -0.4445)
			(size 0.1524 0.1524)
			(layers "F.Cu" "F.Mask" "F.Paste")
			(net "P3V3")
			(options
				(clearance outline)
				(anchor circle)
			)
			(primitives
				(gr_poly
					(pts
						(arc
							(start 0.3048 -0.2032)
							(mid 0.275042 -0.275042)
							(end 0.2032 -0.3048)
						)
						(arc
							(start -0.2032 -0.3048)
							(mid -0.275042 -0.275042)
							(end -0.3048 -0.2032)
						)
						(arc
							(start -0.3048 0.2032)
							(mid -0.275042 0.275042)
							(end -0.2032 0.3048)
						)
						(arc
							(start 0.2032 0.3048)
							(mid 0.275042 0.275042)
							(end 0.3048 0.2032)
						)
					)
					(width 0)
					(fill yes)
				)
			)
		)
		(pad "2" smd custom
			(at 0 0.4445)
			(size 0.1524 0.1524)
			(layers "F.Cu" "F.Mask" "F.Paste")
			(net "GND")
			(options
				(clearance outline)
				(anchor circle)
			)
			(primitives
				(gr_poly
					(pts
						(arc
							(start 0.3048 -0.2032)
							(mid 0.275042 -0.275042)
							(end 0.2032 -0.3048)
						)
						(arc
							(start -0.2032 -0.3048)
							(mid -0.275042 -0.275042)
							(end -0.3048 -0.2032)
						)
						(arc
							(start -0.3048 0.2032)
							(mid -0.275042 0.275042)
							(end -0.2032 0.3048)
						)
						(arc
							(start 0.2032 0.3048)
							(mid 0.275042 0.275042)
							(end 0.3048 0.2032)
						)
					)
					(width 0)
					(fill yes)
				)
			)
		)
	)
)
